# TIMECARD (Time Appliance Project (Time Card)) — schematic parts with pin connectivity, parts 1078–1097 of 1119; source: Cadence DE-HDL packaged netlist (pstxprt.dat, pstxnet.dat, pstchip.dat)

U4  PCA9546APW_TSSOP16  pkg SOP16_173_P0256_H043  page 16
  1  A0  IN  = UNNAMED_5_PCA9546APWTSSOP16_I33
  2  A1  IN  = UNNAMED_5_PCA9546APWTSSOP16_I_1
  3  \reset*\  IN  = PCA9546_RST_N
  4  SD0  BI  = LM75B_I2C_SDA
  5  SC0  BI  = LM75B_I2C_SCL
  6  SD1  BI  = SHT3X_I2C_SDA
  7  SC1  BI  = SHT3X_I2C_SCL
  8  VSS  GROUND  = SG
  9  SD2  BI  = ICP10100_I2C_SDA
  10  SC2  BI  = ICP10100_I2C_SCL
  11  SD3  BI  = BNO080_I2C_SDA
  12  SC3  BI  = BNO080_I2C_SCL
  13  A2  IN  = UNNAMED_5_PCA9546APWTSSOP16_I_2
  14  SCL  BI  = R_PCA9546_I2C_SCL
  15  SDA  BI  = R_PCA9546_I2C_SDA
  16  VDD  POWER  = VDD_PCA9546A

U5  TPS54824RNVR_VQFN18  TPS54424RNVT  pkg QFN18_138_P0197_V1  page 32
  1  BOOT  IN  = XP5R0V_BT
  2  VIN_1  IN  = VIN_XP5R0V
  3  PGND_1  GROUND  = SG
  4  PGND_2  GROUND  = SG
  5  PGND_3  GROUND  = SG
  6  SW_1  OUT  = XP5R0V_SW
  7  SW_2  OUT  = XP5R0V_SW
  8  PGND_4  GROUND  = SG
  9  PGND_5  GROUND  = SG
  10  PGND_6  GROUND  = SG
  11  VIN_2  POWER  = VIN_XP5R0V
  12  AGND  GROUND  = XP5R0V_AGND
  13  \rt/clk\  IN  = XP5R0V_RT
  14  FB  IN  = XP5R0V_FB_R_TO_AGND
  15  COMP  IN  = XP5R0V_COMP
  16  \ss/trk\  IN  = XP5R0V_SS
  17  EN  IN  = R_XP5R0V_EN
  18  PGOOD  OUT  = XP5R0V_PG

U6  TPS54824RNVR_VQFN18  TPS54424RNVT  pkg QFN18_138_P0197_V1  page 28
  1  BOOT  IN  = XP3R3V_BT
  2  VIN_1  IN  = VIN_XP3R3
  3  PGND_1  GROUND  = SG
  4  PGND_2  GROUND  = SG
  5  PGND_3  GROUND  = SG
  6  SW_1  OUT  = XP3R3V_SW
  7  SW_2  OUT  = XP3R3V_SW
  8  PGND_4  GROUND  = SG
  9  PGND_5  GROUND  = SG
  10  PGND_6  GROUND  = SG
  11  VIN_2  POWER  = VIN_XP3R3
  12  AGND  GROUND  = XP3R3V_AGND
  13  \rt/clk\  IN  = XP3R3V_RT
  14  FB  IN  = XP3R3V_FB_R_TO_AGND
  15  COMP  IN  = XP3R3V_COMP
  16  \ss/trk\  IN  = XP3R3V_SS
  17  EN  IN  = XP3R3V_EN
  18  PGOOD  OUT  = R_XP3R3V_PG

U7  AT24MAC402_SOT23_5  AT24MAC602-STUM-T  pkg SOT23_5_H039  page 16
  1  SCL  BI  = EEPROM_SCL
  2  GND  GROUND  = SG
  3  SDA  BI  = PRI_EEPROM_SDA
  4  VCC  POWER  = XP3R3V_FPGA
  5  WP  BI  = SN_EEPROM_WP

U8  LM75BDP_TSSOP8  pkg SOP8_118_P0256_V2  page 17
  1  SDA  BI  = R_LM75B_1_I2C_SDA
  2  SCL  IN  = LM75B_I2C_SCL
  3  OS  OUT  = FPGA_IN_LM75B_INT1_N
  4  GND  GROUND  = SG
  5  A2  IN  = UNNAMED_6_LM75BDPTSSOP8_I34_A2
  6  A1  IN  = UNNAMED_6_LM75BDPTSSOP8_I34_A1
  7  A0  IN  = UNNAMED_6_LM75BDPTSSOP8_I34_A0
  8  VCC  POWER  = XP3R3V_FPGA

U9  CL1001485A  pkg SOT23_6  page 21
  1  \1\  BI  = NC
  2  \2\  BI  = SG
  3  \3\  BI  = NC
  4  \4\  BI  = CONN_MICRO_USB_DM
  5  \5\  BI  = XP5R0V_USB_CONN
  6  \6\  BI  = CONN_MICRO_USB_DP

U10  CL5003148A  pkg SC70_5V1  page 21
  1  A  IN  = FPGA_OUT_MACUSBPOWER_EN
  2  B  IN  = XP5R0V_USB_CONN_DET
  3  GND  GROUND  = SG
  4  Y  OUT  = USB_PWR_EN
  5  VCC  POWER  = XP3R3V_FPGA

U11  TS3USB3031RMGR_WQFN12  TS3USB3031RMGR  pkg QFN12_071_P0157  page 21
  1  SEL0  IN  = XP5R0V_USB_CONN_DET
  2  SEL1  IN  = UNNAMED_527_RESISTOR_I126_1
  3  USB1_P  BI  = MAC_USB_DP
  4  USB1_N  BI  = MAC_USB_DM
  5  USB2_P  BI  = CONN_MICRO_USB_DP
  6  USB2_N  BI  = CONN_MICRO_USB_DM
  7  MHL_P  BI  = NC
  8  MHL_N  BI  = NC
  9  GND  GROUND  = SG
  10  D_N  BI  = MUX_USB_DM
  11  D_P  BI  = MUX_USB_DP
  12  VCC  POWER  = XP3R3V_FPGA

U12  TPS2051BDBVT_SOT23_5  pkg SOT23_5  page 21
  1  \out\  OUT  = XP5R0V_MAC_USB
  2  GND  GROUND  = SG
  3  \oc*\  OUT  = UNNAMED_527_RESISTOR_I206_1
  4  EN  IN  = USB_PWR_EN
  5  \in\  IN  = XP5R0V_MAC

U13  74HCT2G125DP_TSSOP8  NC7WV125K8X  pkg SOP8_091_P0197_H035  page 23
  1  \1oe*\  BI  = SMA3_SIG_OUT_BF_EN_N
  2  \1a\  IN  = UNNAMED_12_74HCT2G125DPTSSOP8_I
  3  \2y\  OUT  = BF_ANT3_IN
  4  GND  GROUND  = SG
  5  \2a\  IN  = BF_SMA3_SIG_IO_CONN
  6  \1y\  OUT  = BF_SMA3_SIG_IO_CONN
  7  \2oe*\  BI  = SMA3_SIG_IN_BF_EN_N
  8  VCC  POWER  = XP3R3V_FPGA

U14  74HCT2G125DP_TSSOP8  NC7WV125K8X  pkg SOP8_091_P0197_H035  page 23
  1  \1oe*\  BI  = SMA4_SIG_OUT_BF_EN_N
  2  \1a\  IN  = UNNAMED_12_74HCT2G125DPTSSOP8_3
  3  \2y\  OUT  = BF_ANT4_IN
  4  GND  GROUND  = SG
  5  \2a\  IN  = BF_SMA4_SIG_IO_CONN
  6  \1y\  OUT  = BF_SMA4_SIG_IO_CONN
  7  \2oe*\  BI  = SMA4_SIG_IN_BF_EN_N
  8  VCC  POWER  = XP3R3V_FPGA

U15  74HCT2G125DP_TSSOP8  NC7WV125K8X  pkg SOP8_091_P0197_H035  page 23
  1  \1oe*\  BI  = SMA1_SIG_OUT_BF_EN_N
  2  \1a\  IN  = UNNAMED_12_74HCT2G125DPTSSOP8_6
  3  \2y\  OUT  = BF_ANT1_IN
  4  GND  GROUND  = SG
  5  \2a\  IN  = BF_SMA1_SIG_IO_CONN
  6  \1y\  OUT  = BF_SMA1_SIG_IO_CONN
  7  \2oe*\  BI  = SMA1_SIG_IN_BF_EN_N
  8  VCC  POWER  = XP3R3V_FPGA

U16  74HCT2G125DP_TSSOP8  NC7WV125K8X  pkg SOP8_091_P0197_H035  page 23
  1  \1oe*\  BI  = SMA2_SIG_OUT_BF_EN_N
  2  \1a\  IN  = UNNAMED_12_74HCT2G125DPTSSOP8_9
  3  \2y\  OUT  = BF_ANT2_IN
  4  GND  GROUND  = SG
  5  \2a\  IN  = BF_SMA2_SIG_IO_CONN
  6  \1y\  OUT  = BF_SMA2_SIG_IO_CONN
  7  \2oe*\  BI  = SMA2_SIG_IN_BF_EN_N
  8  VCC  POWER  = XP3R3V_FPGA

U17  CL1001485A  pkg SOT23_6  page 24
  1  \1\  BI  = NC
  2  \2\  BI  = SG
  3  \3\  BI  = NC
  4  \4\  BI  = FT_USB_DM
  5  \5\  BI  = XP5R0V_FT4232
  6  \6\  BI  = FT_USB_DP

U18  FT4232HL_REEL_QFP64  FT4232HL-REEL  pkg QFP64_394_P0197_V1  page 24
  1  GND_8  GROUND  = SG
  2  OSCI  BI  = UNNAMED_524_CAPACITOR_I7_2
  3  OSCO  BI  = UNNAMED_524_CAPACITOR_I10_2
  4  VPHY  BI  = XP3R3V_VPHY
  5  GND_7  GROUND  = SG
  6  REF  IN  = UNNAMED_524_FT4232HLREELQFP64_6
  7  DM  BI  = R_FT_USB_DM
  8  DP  BI  = R_FT_USB_DP
  9  VPLL  BI  = XP3R3V_VPLL
  10  AGND  GROUND  = SG
  11  GND_6  GROUND  = SG
  12  VCORE_3  POWER  = FT4232_VREGOUT
  13  TEST  BI  = SG
  14  \reset*\  BI  = UNNAMED_524_FT4232HLREELQFP64_7
  15  GND_5  GROUND  = SG
  16  ADBUS0  BI  = R_FT4232_TCK
  17  ADBUS1  BI  = R_FT4232_TDI
  18  ADBUS2  BI  = R_FT4232_TDO
  19  ADBUS3  BI  = R_FT4232_TMS
  20  VCCIO_4  POWER  = XP3R3V_FT4232
  21  ADBUS4  BI  = FT4232_MUX1_SEL
  22  ADBUS5  BI  = FT4232_MUX2_SEL
  23  ADBUS6  BI  = FT4232_MUX3_SEL
  24  ADBUS7  BI  = UNNAMED_524_FT4232HLREELQFP64_I
  25  GND_4  GROUND  = SG
  26  BDBUS0  BI  = R_FT4232_I2C_SCL
  27  BDBUS1  BI  = R_FT4232_I2C_SDA_OUT
  28  BDBUS2  BI  = R_FT4232_I2C_SDA_IN
  29  BDBUS3  BI  = UNNAMED_524_FT4232HLREELQFP64_1
  30  BDBUS4  BI  = UNNAMED_524_FT4232HLREELQFP64_2
  31  VCCIO_3  POWER  = XP3R3V_FT4232
  32  BDBUS5  BI  = UNNAMED_524_FT4232HLREELQFP64_3
  33  BDBUS6  BI  = UNNAMED_524_FT4232HLREELQFP64_4
  34  BDBUS7  BI  = UNNAMED_524_FT4232HLREELQFP64_5
  35  GND_3  GROUND  = SG
  36  \suspend*\  BI  = NC
  37  VCORE_2  POWER  = FT4232_VREGOUT
  38  CDBUS0  BI  = R_FT4232_CHC_TX
  39  CDBUS1  BI  = R_FT4232_CHC_RX
  40  CDBUS2  BI  = NC
  41  CDBUS3  BI  = NC
  42  VCCIO_2  POWER  = XP3R3V_FT4232
  43  CDBUS4  BI  = NC
  44  CDBUS5  BI  = NC
  45  CDBUS6  BI  = NC
  46  CDBUS7  BI  = NC
  47  GND_2  GROUND  = SG
  48  DDBUS0  BI  = R_FT4232_CHD_TX
  49  VREGOUT  OUT  = FT4232_VREGOUT
  50  VREGIN  IN  = XP3R3V_FT4232
  51  GND_1  GROUND  = SG
  52  DDBUS1  BI  = R_FT4232_CHD_RX
  53  DDBUS2  BI  = NC
  54  DDBUS3  BI  = NC
  55  DDBUS4  BI  = NC
  56  VCCIO_1  POWER  = XP3R3V_FT4232
  57  DDBUS5  BI  = NC
  58  DDBUS6  BI  = NC
  59  DDBUS7  BI  = NC
  60  \pwren*\  BI  = NC
  61  EEDATA  BI  = FTDI_EE_DAT
  62  EECLK  BI  = FTDI_EE_CLK
  63  EECS  BI  = FTDI_EE_CS
  64  VCORE_1  POWER  = FT4232_VREGOUT

U19  24LC16BT_I_ST_TSSOP8  pkg SOP8_173X118_P0256  page 16
  1  A0  BI  = UNNAMED_5_24LC16BTISTTSSOP8_I15
  2  A1  BI  = UNNAMED_5_24LC16BTISTTSSOP8_I_1
  3  A2  BI  = UNNAMED_5_24LC16BTISTTSSOP8_I_2
  4  VSS  GROUND  = SG
  5  SDA  BI  = SEC_EEPROM_SDA
  6  SCL  IN  = EEPROM_SCL
  7  WP  IN  = SEC_EEPROM_WP
  8  VCC  POWER  = XP3R3V_FPGA

U20  ISL80101IRAJZ_DFN10  pkg DFN11_118_P0197_TR057X071  page 30
  1  VOUT_1  OUT  = XP1R2V_FPGA
  2  VOUT_2  OUT  = XP1R2V_FPGA
  3  \sense/adj\  BI  = XP1R2V_FB
  4  PG  BI  = XP1R2V_PG_R
  5  GND  GROUND  = SG
  6  SS  BI  = XP1R2V_SS
  7  ENABLE  BI  = XP1R2V_EN_R
  8  NC  NC  = NC
  9  VIN_1  IN  = XP1R2V_VIN
  10  VIN_2  IN  = XP1R2V_VIN
  11  THRM_PAD  GROUND  = SG

U21  ISL80101IRAJZ_DFN10  pkg DFN11_118_P0197_TR057X071  page 30
  1  VOUT_1  OUT  = XP1R8V_FPGA
  2  VOUT_2  OUT  = XP1R8V_FPGA
  3  \sense/adj\  BI  = XP1R8V_FB
  4  PG  BI  = XP1R8V_PG_R
  5  GND  GROUND  = SG
  6  SS  BI  = XP1R8V_SS
  7  ENABLE  BI  = XP1R8V_EN_R
  8  NC  NC  = NC
  9  VIN_1  IN  = XP1R8V_VIN
  10  VIN_2  IN  = XP1R8V_VIN
  11  THRM_PAD  GROUND  = SG

U22  NCP45560IMNTWG_H_DFN12  pkg DFN13_118_P0197_TR071X096  page 31
  1  VIN_1  BI  = XP3R3V
  2  EN  BI  = XP3R3V_FPGA_EN_R
  3  VCC  POWER  = XP3R3V
  4  GND  GROUND  = SG
  5  SR  BI  = XP3R3V_FPGA_SR
  6  PG  BI  = UNNAMED_515_NCP45560IMNTWGHDFN1
  7  BLEED  BI  = XP3R3V_FPGA
  8  VOUT_1  BI  = XP3R3V_FPGA
  9  VOUT_2  BI  = XP3R3V_FPGA
  10  VOUT_3  BI  = XP3R3V_FPGA
  11  VOUT_4  BI  = XP3R3V_FPGA
  12  VOUT_5  BI  = XP3R3V_FPGA
  13  VIN_2  BI  = XP3R3V

U23  MT25QL128ABA1ESE_SOP8  MT25QL128ABA1ESE-0SIT  pkg SOP8_208_P050_V2  page 10
  1  \s*\  IN  = FLASH_CS_N
  2  DQ1  BI  = UNNAMED_127_MT25QL128ABA1ESES_1
  3  \w/dq2*\  BI  = UNNAMED_127_MT25QL128ABA1ESES_3
  4  VSS  GROUND  = SG
  5  DQ0  BI  = UNNAMED_127_MT25QL128ABA1ESESOP
  6  C  IN  = FLASH_CLK
  7  \hold/dq3*\  BI  = UNNAMED_127_MT25QL128ABA1ESES_2
  8  VCC  POWER  = XP3R3V_FPGA
